(kicad_pcb
	(version 20260206)
	(generator "pcbnew")
	(generator_version "10.0")
	(general
		(thickness 1.6)
		(legacy_teardrops no)
	)
	(paper "A4")
	(title_block
		(title "baseboard — 13948-1b.1110WZS1818.brd")
		(comment 1 "Honey Badger (Wiwynn) / footprints 768-776 of 2523")
	)
	(layers
		(0 "F.Cu" signal "TOP")
		(4 "In1.Cu" signal "L2GND")
		(6 "In2.Cu" signal "L3")
		(8 "In3.Cu" signal "L4VCC")
		(10 "In4.Cu" signal "L5VCC")
		(12 "In5.Cu" signal "L6")
		(14 "In6.Cu" signal "L7GND")
		(2 "B.Cu" signal "BOTTOM")
		(9 "F.Adhes" user "F.Adhesive")
		(11 "B.Adhes" user "B.Adhesive")
		(13 "F.Paste" user "Package Geometry/Pastemask Top")
		(15 "B.Paste" user "Package Geometry/Pastemask Bottom")
		(5 "F.SilkS" user "Ref Des/Silkscreen Top")
		(7 "B.SilkS" user "Ref Des/Silkscreen Bottom")
		(1 "F.Mask" user "Board Geometry/Soldermask Top")
		(3 "B.Mask" user "Board Geometry/Soldermask Bottom")
		(17 "Dwgs.User" user "User.Drawings")
		(19 "Cmts.User" user "User.Comments")
		(21 "Eco1.User" user "User.Eco1")
		(23 "Eco2.User" user "User.Eco2")
		(25 "Edge.Cuts" user "Board Geometry/Outline")
		(27 "Margin" user)
		(31 "F.CrtYd" user "Package Geometry/Place Bound Top")
		(29 "B.CrtYd" user "Package Geometry/Place Bound Bottom")
		(35 "F.Fab" user "Ref Des/Assembly Top")
		(33 "B.Fab" user "Ref Des/Assembly Bottom")
	)
	(footprint ""
		(layer "F.Cu")
		(at 92.21597 -100.076 -90)
		(property "Reference" "SR776"
			(at 0 0 270)
			(layer "F.SilkS")
			(hide yes)
			(effects
				(font
					(size 1.27 1.27)
				)
			)
		)
		(property "Value" "4K7R2F-GP"
			(at 0.064008 -3.993896 270)
			(unlocked yes)
			(layer "F.Fab")
			(hide yes)
			(effects
				(font
					(size 1.016 1.016)
					(thickness 0.1524)
				)
			)
		)
		(property "Device Type" "R402H16"
			(at 0.064008 -5.517896 270)
			(unlocked yes)
			(layer "F.Fab")
			(hide yes)
			(effects
				(font
					(size 1.016 1.016)
					(thickness 0.1524)
				)
			)
		)
		(duplicate_pad_numbers_are_jumpers no)
		(fp_line
			(start -0.508 -0.9398)
			(end -0.508 0.9398)
			(stroke
				(width 0.1524)
				(type default)
			)
			(layer "F.SilkS")
		)
		(fp_line
			(start 0.508 -0.9398)
			(end -0.508 -0.9398)
			(stroke
				(width 0.1524)
				(type default)
			)
			(layer "F.SilkS")
		)
		(fp_rect
			(start -0.508 0.9398)
			(end 0.508 -0.9398)
			(stroke
				(width 0)
				(type default)
			)
			(fill no)
			(layer "F.CrtYd")
		)
		(fp_rect
			(start -0.508 0.9398)
			(end 0.508 -0.9398)
			(stroke
				(width 0)
				(type default)
			)
			(fill no)
			(layer "F.Fab")
		)
		(pad "1" smd custom
			(at 0 -0.4445 270)
			(size 0.1397 0.1397)
			(layers "F.Cu" "F.Mask" "F.Paste")
			(net "EXP_XM_ADDR_15")
			(options
				(clearance outline)
				(anchor circle)
			)
			(primitives
				(gr_poly
					(pts
						(arc
							(start -0.1778 -0.2794)
							(mid -0.249642 -0.249642)
							(end -0.2794 -0.1778)
						)
						(arc
							(start -0.2794 0.1778)
							(mid -0.249642 0.249642)
							(end -0.1778 0.2794)
						)
						(arc
							(start 0.1778 0.2794)
							(mid 0.249642 0.249642)
							(end 0.2794 0.1778)
						)
						(arc
							(start 0.2794 -0.1778)
							(mid 0.249642 -0.249642)
							(end 0.1778 -0.2794)
						)
					)
					(width 0)
					(fill yes)
				)
			)
		)
		(pad "2" smd custom
			(at 0 0.4445 270)
			(size 0.1397 0.1397)
			(layers "F.Cu" "F.Mask" "F.Paste")
			(net "GND")
			(options
				(clearance outline)
				(anchor circle)
			)
			(primitives
				(gr_poly
					(pts
						(arc
							(start -0.1778 -0.2794)
							(mid -0.249642 -0.249642)
							(end -0.2794 -0.1778)
						)
						(arc
							(start -0.2794 0.1778)
							(mid -0.249642 0.249642)
							(end -0.1778 0.2794)
						)
						(arc
							(start 0.1778 0.2794)
							(mid 0.249642 0.249642)
							(end 0.2794 0.1778)
						)
						(arc
							(start 0.2794 -0.1778)
							(mid 0.249642 -0.249642)
							(end 0.1778 -0.2794)
						)
					)
					(width 0)
					(fill yes)
				)
			)
		)
	)
	(footprint ""
		(layer "F.Cu")
		(at 22.302216 -213.79688)
		(property "Reference" "R633"
			(at 0 0 0)
			(layer "F.SilkS")
			(hide yes)
			(effects
				(font
					(size 1.27 1.27)
				)
			)
		)
		(property "Value" "4K7R2F-GP"
			(at 0.064008 -3.993896 0)
			(unlocked yes)
			(layer "F.Fab")
			(hide yes)
			(effects
				(font
					(size 1.016 1.016)
					(thickness 0.1524)
				)
			)
		)
		(property "Device Type" "R402H16"
			(at 0.064008 -5.517896 0)
			(unlocked yes)
			(layer "F.Fab")
			(hide yes)
			(effects
				(font
					(size 1.016 1.016)
					(thickness 0.1524)
				)
			)
		)
		(duplicate_pad_numbers_are_jumpers no)
		(fp_line
			(start -0.508 -0.9398)
			(end -0.508 0.9398)
			(stroke
				(width 0.1524)
				(type default)
			)
			(layer "F.SilkS")
		)
		(fp_line
			(start 0.508 -0.9398)
			(end -0.508 -0.9398)
			(stroke
				(width 0.1524)
				(type default)
			)
			(layer "F.SilkS")
		)
		(fp_rect
			(start -0.508 0.9398)
			(end 0.508 -0.9398)
			(stroke
				(width 0)
				(type default)
			)
			(fill no)
			(layer "F.CrtYd")
		)
		(fp_rect
			(start -0.508 0.9398)
			(end 0.508 -0.9398)
			(stroke
				(width 0)
				(type default)
			)
			(fill no)
			(layer "F.Fab")
		)
		(pad "1" smd custom
			(at 0 -0.4445)
			(size 0.1397 0.1397)
			(layers "F.Cu" "F.Mask" "F.Paste")
			(net "IO_EXP_HDD_PWR_A1")
			(options
				(clearance outline)
				(anchor circle)
			)
			(primitives
				(gr_poly
					(pts
						(arc
							(start -0.1778 -0.2794)
							(mid -0.249642 -0.249642)
							(end -0.2794 -0.1778)
						)
						(arc
							(start -0.2794 0.1778)
							(mid -0.249642 0.249642)
							(end -0.1778 0.2794)
						)
						(arc
							(start 0.1778 0.2794)
							(mid 0.249642 0.249642)
							(end 0.2794 0.1778)
						)
						(arc
							(start 0.2794 -0.1778)
							(mid 0.249642 -0.249642)
							(end 0.1778 -0.2794)
						)
					)
					(width 0)
					(fill yes)
				)
			)
		)
		(pad "2" smd custom
			(at 0 0.4445)
			(size 0.1397 0.1397)
			(layers "F.Cu" "F.Mask" "F.Paste")
			(net "GND")
			(options
				(clearance outline)
				(anchor circle)
			)
			(primitives
				(gr_poly
					(pts
						(arc
							(start -0.1778 -0.2794)
							(mid -0.249642 -0.249642)
							(end -0.2794 -0.1778)
						)
						(arc
							(start -0.2794 0.1778)
							(mid -0.249642 0.249642)
							(end -0.1778 0.2794)
						)
						(arc
							(start 0.1778 0.2794)
							(mid 0.249642 0.249642)
							(end 0.2794 0.1778)
						)
						(arc
							(start 0.2794 -0.1778)
							(mid 0.249642 -0.249642)
							(end 0.1778 -0.2794)
						)
					)
					(width 0)
					(fill yes)
				)
			)
		)
	)
	(footprint ""
		(layer "F.Cu")
		(at 78.10119 -62.705488 180)
		(property "Reference" "SL5"
			(at 0 0 180)
			(layer "F.SilkS")
			(hide yes)
			(effects
				(font
					(size 1.27 1.27)
				)
			)
		)
		(property "Value" "MPZ2012S601AT-GP"
			(at 0 -4.2418 180)
			(unlocked yes)
			(layer "F.Fab")
			(hide yes)
			(effects
				(font
					(size 1.016 1.016)
					(thickness 0.1524)
				)
			)
		)
		(property "Device Type" "L805H42"
			(at 0 -5.7912 180)
			(unlocked yes)
			(layer "F.Fab")
			(hide yes)
			(effects
				(font
					(size 1.016 1.016)
					(thickness 0.1524)
				)
			)
		)
		(duplicate_pad_numbers_are_jumpers no)
		(fp_line
			(start 0.889 1.7018)
			(end -0.889 1.7018)
			(stroke
				(width 0.1524)
				(type default)
			)
			(layer "F.SilkS")
		)
		(fp_line
			(start 0.889 -1.7018)
			(end 0.889 1.7018)
			(stroke
				(width 0.1524)
				(type default)
			)
			(layer "F.SilkS")
		)
		(fp_line
			(start -0.889 1.7018)
			(end -0.889 -1.7018)
			(stroke
				(width 0.1524)
				(type default)
			)
			(layer "F.SilkS")
		)
		(fp_line
			(start -0.889 -1.7018)
			(end 0.889 -1.7018)
			(stroke
				(width 0.1524)
				(type default)
			)
			(layer "F.SilkS")
		)
		(fp_rect
			(start -0.9652 1.778)
			(end 0.9652 -1.778)
			(stroke
				(width 0)
				(type default)
			)
			(fill no)
			(layer "F.CrtYd")
		)
		(fp_rect
			(start -0.9652 1.778)
			(end 0.9652 -1.778)
			(stroke
				(width 0)
				(type default)
			)
			(fill no)
			(layer "F.Fab")
		)
		(pad "1" smd rect
			(at 0 -0.9652 180)
			(size 1.397 1.143)
			(layers "F.Cu" "F.Mask" "F.Paste")
			(net "SHELL_PLL_VDD")
		)
		(pad "2" smd rect
			(at 0 0.9652 180)
			(size 1.397 1.143)
			(layers "F.Cu" "F.Mask" "F.Paste")
			(net "P1V8_C")
		)
	)
	(footprint ""
		(layer "F.Cu")
		(at 118.237 -31.115)
		(property "Reference" "STP131"
			(at 0 0 0)
			(layer "F.SilkS")
			(hide yes)
			(effects
				(font
					(size 1.27 1.27)
				)
			)
		)
		(property "Value" "TPAD28"
			(at 0.0127 -1.8034 0)
			(unlocked yes)
			(layer "F.Fab")
			(hide yes)
			(effects
				(font
					(size 1.016 1.016)
					(thickness 0.1524)
				)
			)
		)
		(property "Device Type" "TPAD28"
			(at 0.0127 -3.3274 0)
			(unlocked yes)
			(layer "F.Fab")
			(hide yes)
			(effects
				(font
					(size 1.016 1.016)
					(thickness 0.1524)
				)
			)
		)
		(duplicate_pad_numbers_are_jumpers no)
		(fp_poly
			(pts
				(arc
					(start 0.3556 0)
					(mid -0.3556 0)
					(end 0.3556 0)
				)
			)
			(stroke
				(width 0)
				(type default)
			)
			(fill no)
			(layer "F.CrtYd")
		)
		(fp_poly
			(pts
				(arc
					(start 0.6096 0)
					(mid -0.6096 0)
					(end 0.6096 0)
				)
			)
			(stroke
				(width 0)
				(type default)
			)
			(fill no)
			(layer "F.Fab")
		)
		(pad "1" smd circle
			(at 0 0)
			(size 0.7112 0.7112)
			(layers "F.Cu" "F.Mask" "F.Paste")
			(net "IOC_GPIO_4")
		)
	)
	(footprint ""
		(layer "F.Cu")
		(at 116.85397 -79.248)
		(property "Reference" "STP110"
			(at 0 0 0)
			(layer "F.SilkS")
			(hide yes)
			(effects
				(font
					(size 1.27 1.27)
				)
			)
		)
		(property "Value" "TPAD28"
			(at 0.0127 -1.8034 0)
			(unlocked yes)
			(layer "F.Fab")
			(hide yes)
			(effects
				(font
					(size 1.016 1.016)
					(thickness 0.1524)
				)
			)
		)
		(property "Device Type" "TPAD28"
			(at 0.0127 -3.3274 0)
			(unlocked yes)
			(layer "F.Fab")
			(hide yes)
			(effects
				(font
					(size 1.016 1.016)
					(thickness 0.1524)
				)
			)
		)
		(duplicate_pad_numbers_are_jumpers no)
		(fp_poly
			(pts
				(arc
					(start 0.3556 0)
					(mid -0.3556 0)
					(end 0.3556 0)
				)
			)
			(stroke
				(width 0)
				(type default)
			)
			(fill no)
			(layer "F.CrtYd")
		)
		(fp_poly
			(pts
				(arc
					(start 0.6096 0)
					(mid -0.6096 0)
					(end 0.6096 0)
				)
			)
			(stroke
				(width 0)
				(type default)
			)
			(fill no)
			(layer "F.Fab")
		)
		(pad "1" smd circle
			(at 0 0)
			(size 0.7112 0.7112)
			(layers "F.Cu" "F.Mask" "F.Paste")
			(net "TEST_MUX_43")
		)
	)
	(footprint ""
		(layer "F.Cu")
		(at 347.345 -92.075 90)
		(property "Reference" "PC18"
			(at 0 0 90)
			(layer "F.SilkS")
			(hide yes)
			(effects
				(font
					(size 1.27 1.27)
				)
			)
		)
		(property "Value" "SC47U10V6MX-GP"
			(at -0.0762 -5.1308 90)
			(unlocked yes)
			(layer "F.Fab")
			(hide yes)
			(effects
				(font
					(size 1.016 1.016)
					(thickness 0.1524)
				)
			)
		)
		(property "Device Type" "C1206H71"
			(at -0.127 -6.6548 90)
			(unlocked yes)
			(layer "F.Fab")
			(hide yes)
			(effects
				(font
					(size 1.016 1.016)
					(thickness 0.1524)
				)
			)
		)
		(duplicate_pad_numbers_are_jumpers no)
		(fp_line
			(start 1.016 -2.2352)
			(end 1.016 -0.8382)
			(stroke
				(width 0.1524)
				(type default)
			)
			(layer "F.SilkS")
		)
		(fp_line
			(start -1.016 -2.2352)
			(end 1.016 -2.2352)
			(stroke
				(width 0.1524)
				(type default)
			)
			(layer "F.SilkS")
		)
		(fp_line
			(start -1.016 -0.8382)
			(end -1.016 -2.2352)
			(stroke
				(width 0.1524)
				(type default)
			)
			(layer "F.SilkS")
		)
		(fp_line
			(start 1.016 0.8382)
			(end 1.016 2.2352)
			(stroke
				(width 0.1524)
				(type default)
			)
			(layer "F.SilkS")
		)
		(fp_line
			(start 1.016 2.2352)
			(end -1.016 2.2352)
			(stroke
				(width 0.1524)
				(type default)
			)
			(layer "F.SilkS")
		)
		(fp_line
			(start -1.016 2.2352)
			(end -1.016 0.8382)
			(stroke
				(width 0.1524)
				(type default)
			)
			(layer "F.SilkS")
		)
		(fp_rect
			(start -1.0922 2.3114)
			(end 1.0922 -2.3114)
			(stroke
				(width 0)
				(type default)
			)
			(fill no)
			(layer "F.CrtYd")
		)
		(fp_poly
			(pts
				(xy 1.0922 -2.3114) (xy 1.0922 2.3114) (xy -1.0922 2.3114) (xy -1.0922 -2.3114)
			)
			(stroke
				(width 0)
				(type default)
			)
			(fill no)
			(layer "F.Fab")
		)
		(pad "1" smd rect
			(at 0 -1.397 90)
			(size 1.651 1.27)
			(layers "F.Cu" "F.Mask" "F.Paste")
			(net "P5V_STBY")
		)
		(pad "2" smd rect
			(at 0 1.397 90)
			(size 1.651 1.27)
			(layers "F.Cu" "F.Mask" "F.Paste")
			(net "GND")
		)
	)
	(footprint ""
		(layer "F.Cu")
		(at 344.805 -117.729)
		(property "Reference" "PR9"
			(at 0 0 0)
			(layer "F.SilkS")
			(hide yes)
			(effects
				(font
					(size 1.27 1.27)
				)
			)
		)
		(property "Value" "10R3F-GP"
			(at -0.0254 -2.5146 0)
			(unlocked yes)
			(layer "F.Fab")
			(hide yes)
			(effects
				(font
					(size 1.016 1.016)
					(thickness 0.1524)
				)
			)
		)
		(property "Device Type" "R603H22"
			(at -0.0254 -4.0386 0)
			(unlocked yes)
			(layer "F.Fab")
			(hide yes)
			(effects
				(font
					(size 1.016 1.016)
					(thickness 0.1524)
				)
			)
		)
		(duplicate_pad_numbers_are_jumpers no)
		(fp_line
			(start -0.4826 0)
			(end -0.2032 0)
			(stroke
				(width 0.2032)
				(type default)
			)
			(layer "F.SilkS")
		)
		(fp_line
			(start 0.2032 0)
			(end 0.4826 0)
			(stroke
				(width 0.2032)
				(type default)
			)
			(layer "F.SilkS")
		)
		(fp_rect
			(start -0.5842 1.3335)
			(end 0.5842 -1.3335)
			(stroke
				(width 0)
				(type default)
			)
			(fill no)
			(layer "F.CrtYd")
		)
		(fp_rect
			(start -0.5842 1.3335)
			(end 0.5842 -1.3335)
			(stroke
				(width 0)
				(type default)
			)
			(fill no)
			(layer "F.Fab")
		)
		(pad "1" smd custom
			(at 0 -0.762)
			(size 0.2159 0.2159)
			(layers "F.Cu" "F.Mask" "F.Paste")
			(net "P5V_STBY_CC")
			(options
				(clearance outline)
				(anchor circle)
			)
			(primitives
				(gr_poly
					(pts
						(arc
							(start -0.3302 -0.4318)
							(mid -0.402042 -0.402042)
							(end -0.4318 -0.3302)
						)
						(arc
							(start -0.4318 0.3302)
							(mid -0.402042 0.402042)
							(end -0.3302 0.4318)
						)
						(arc
							(start 0.3302 0.4318)
							(mid 0.402042 0.402042)
							(end 0.4318 0.3302)
						)
						(arc
							(start 0.4318 -0.3302)
							(mid 0.402042 -0.402042)
							(end 0.3302 -0.4318)
						)
					)
					(width 0)
					(fill yes)
				)
			)
		)
		(pad "2" smd custom
			(at 0 0.762)
			(size 0.2159 0.2159)
			(layers "F.Cu" "F.Mask" "F.Paste")
			(net "P5V_STBY_CC_R")
			(options
				(clearance outline)
				(anchor circle)
			)
			(primitives
				(gr_poly
					(pts
						(arc
							(start -0.3302 -0.4318)
							(mid -0.402042 -0.402042)
							(end -0.4318 -0.3302)
						)
						(arc
							(start -0.4318 0.3302)
							(mid -0.402042 0.402042)
							(end -0.3302 0.4318)
						)
						(arc
							(start 0.3302 0.4318)
							(mid 0.402042 0.402042)
							(end 0.4318 0.3302)
						)
						(arc
							(start 0.4318 -0.3302)
							(mid 0.402042 -0.402042)
							(end 0.3302 -0.4318)
						)
					)
					(width 0)
					(fill yes)
				)
			)
		)
	)
	(footprint ""
		(layer "F.Cu")
		(at 85.852 -242.443 180)
		(property "Reference" "SR951"
			(at 0 0 180)
			(layer "F.SilkS")
			(hide yes)
			(effects
				(font
					(size 1.27 1.27)
				)
			)
		)
		(property "Value" "4K7R2F-GP"
			(at 0.064008 -3.993896 180)
			(unlocked yes)
			(layer "F.Fab")
			(hide yes)
			(effects
				(font
					(size 1.016 1.016)
					(thickness 0.1524)
				)
			)
		)
		(property "Device Type" "R402H16"
			(at 0.064008 -5.517896 180)
			(unlocked yes)
			(layer "F.Fab")
			(hide yes)
			(effects
				(font
					(size 1.016 1.016)
					(thickness 0.1524)
				)
			)
		)
		(duplicate_pad_numbers_are_jumpers no)
		(fp_line
			(start 0.508 -0.9398)
			(end -0.508 -0.9398)
			(stroke
				(width 0.1524)
				(type default)
			)
			(layer "F.SilkS")
		)
		(fp_line
			(start -0.508 -0.9398)
			(end -0.508 0.9398)
			(stroke
				(width 0.1524)
				(type default)
			)
			(layer "F.SilkS")
		)
		(fp_rect
			(start -0.508 0.9398)
			(end 0.508 -0.9398)
			(stroke
				(width 0)
				(type default)
			)
			(fill no)
			(layer "F.CrtYd")
		)
		(fp_rect
			(start -0.508 0.9398)
			(end 0.508 -0.9398)
			(stroke
				(width 0)
				(type default)
			)
			(fill no)
			(layer "F.Fab")
		)
		(pad "1" smd custom
			(at 0 -0.4445 180)
			(size 0.1397 0.1397)
			(layers "F.Cu" "F.Mask" "F.Paste")
			(net "SAS_FAULT_LED10")
			(options
				(clearance outline)
				(anchor circle)
			)
			(primitives
				(gr_poly
					(pts
						(arc
							(start -0.1778 -0.2794)
							(mid -0.249642 -0.249642)
							(end -0.2794 -0.1778)
						)
						(arc
							(start -0.2794 0.1778)
							(mid -0.249642 0.249642)
							(end -0.1778 0.2794)
						)
						(arc
							(start 0.1778 0.2794)
							(mid 0.249642 0.249642)
							(end 0.2794 0.1778)
						)
						(arc
							(start 0.2794 -0.1778)
							(mid 0.249642 -0.249642)
							(end 0.1778 -0.2794)
						)
					)
					(width 0)
					(fill yes)
				)
			)
		)
		(pad "2" smd custom
			(at 0 0.4445 180)
			(size 0.1397 0.1397)
			(layers "F.Cu" "F.Mask" "F.Paste")
			(net "P3V3_STBY")
			(options
				(clearance outline)
				(anchor circle)
			)
			(primitives
				(gr_poly
					(pts
						(arc
							(start -0.1778 -0.2794)
							(mid -0.249642 -0.249642)
							(end -0.2794 -0.1778)
						)
						(arc
							(start -0.2794 0.1778)
							(mid -0.249642 0.249642)
							(end -0.1778 0.2794)
						)
						(arc
							(start 0.1778 0.2794)
							(mid 0.249642 0.249642)
							(end 0.2794 0.1778)
						)
						(arc
							(start 0.2794 -0.1778)
							(mid 0.249642 -0.249642)
							(end 0.1778 -0.2794)
						)
					)
					(width 0)
					(fill yes)
				)
			)
		)
	)
	(footprint ""
		(layer "F.Cu")
		(at 184.776872 -203.703936 -90)
		(property "Reference" "R425"
			(at 0 0 270)
			(layer "F.SilkS")
			(hide yes)
			(effects
				(font
					(size 1.27 1.27)
				)
			)
		)
		(property "Value" "4K7R2J-2-GP"
			(at 0.064008 -3.993896 270)
			(unlocked yes)
			(layer "F.Fab")
			(hide yes)
			(effects
				(font
					(size 1.016 1.016)
					(thickness 0.1524)
				)
			)
		)
		(property "Device Type" "R402H16"
			(at 0.064008 -5.517896 270)
			(unlocked yes)
			(layer "F.Fab")
			(hide yes)
			(effects
				(font
					(size 1.016 1.016)
					(thickness 0.1524)
				)
			)
		)
		(duplicate_pad_numbers_are_jumpers no)
		(fp_line
			(start -0.508 -0.9398)
			(end -0.508 0.9398)
			(stroke
				(width 0.1524)
				(type default)
			)
			(layer "F.SilkS")
		)
		(fp_line
			(start 0.508 -0.9398)
			(end -0.508 -0.9398)
			(stroke
				(width 0.1524)
				(type default)
			)
			(layer "F.SilkS")
		)
		(fp_rect
			(start -0.508 0.9398)
			(end 0.508 -0.9398)
			(stroke
				(width 0)
				(type default)
			)
			(fill no)
			(layer "F.CrtYd")
		)
		(fp_rect
			(start -0.508 0.9398)
			(end 0.508 -0.9398)
			(stroke
				(width 0)
				(type default)
			)
			(fill no)
			(layer "F.Fab")
		)
		(pad "1" smd custom
			(at 0 -0.4445 270)
			(size 0.1397 0.1397)
			(layers "F.Cu" "F.Mask" "F.Paste")
			(net "P3V3_STBY")
			(options
				(clearance outline)
				(anchor circle)
			)
			(primitives
				(gr_poly
					(pts
						(arc
							(start -0.1778 -0.2794)
							(mid -0.249642 -0.249642)
							(end -0.2794 -0.1778)
						)
						(arc
							(start -0.2794 0.1778)
							(mid -0.249642 0.249642)
							(end -0.1778 0.2794)
						)
						(arc
							(start 0.1778 0.2794)
							(mid 0.249642 0.249642)
							(end 0.2794 0.1778)
						)
						(arc
							(start 0.2794 -0.1778)
							(mid 0.249642 -0.249642)
							(end 0.1778 -0.2794)
						)
					)
					(width 0)
					(fill yes)
				)
			)
		)
		(pad "2" smd custom
			(at 0 0.4445 270)
			(size 0.1397 0.1397)
			(layers "F.Cu" "F.Mask" "F.Paste")
			(net "SAS_I2C_B_BUF_SDA")
			(options
				(clearance outline)
				(anchor circle)
			)
			(primitives
				(gr_poly
					(pts
						(arc
							(start -0.1778 -0.2794)
							(mid -0.249642 -0.249642)
							(end -0.2794 -0.1778)
						)
						(arc
							(start -0.2794 0.1778)
							(mid -0.249642 0.249642)
							(end -0.1778 0.2794)
						)
						(arc
							(start 0.1778 0.2794)
							(mid 0.249642 0.249642)
							(end 0.2794 0.1778)
						)
						(arc
							(start 0.2794 -0.1778)
							(mid 0.249642 -0.249642)
							(end 0.1778 -0.2794)
						)
					)
					(width 0)
					(fill yes)
				)
			)
		)
	)
)
